#ISCELL
  mstr_misc dns *
  *
#ISCELL
  mstr_symbols intel_corp_bpage *
  *
#ISCELL
  mstr_standard offpage *
  page207_i1
#CELL
  mstr_discrete inductor *
  page207_i10
#ISCELL
  mstr_standard offpage *
  page207_i11
#ISCELL
  mstr_standard offpage *
  page207_i13
#ISCELL
  mstr_symbols pvccin_cpu1 *
  page207_i14
#CELL
  mstr_discrete inductor *
  page207_i16
#ISCELL
  mstr_symbols gnd *
  page207_i17
#CELL
  dev_discrete cap_a *
  page207_i18
#ISCELL
  mstr_symbols gnd *
  page207_i19
#CELL
  mstr_discrete ir354xx *
  page207_i20
#ISCELL
  mstr_symbols gnd *
  page207_i23
#CELL
  mstr_discrete ir354xx *
  page207_i24
#CELL
  mstr_discrete res *
  page207_i26
#ISCELL
  mstr_symbols vcc_core *
  page207_i27
#CELL
  mstr_discrete cap *
  page207_i28
#CELL
  dev_discrete cap_a *
  page207_i29
#ISCELL
  mstr_standard offpage *
  page207_i3
#CELL
  mstr_discrete cap *
  page207_i30
#CELL
  mstr_discrete cap *
  page207_i32
#CELL
  dev_discrete cap_a *
  page207_i33
#CELL
  mstr_discrete cap *
  page207_i34
#CELL
  mstr_discrete cap *
  page207_i36
#CELL
  dev_discrete cap_a *
  page207_i37
#CELL
  mstr_discrete cap *
  page207_i38
#CELL
  mstr_discrete res *
  page207_i39
#CELL
  mstr_discrete cap *
  page207_i40
#CELL
  dev_discrete cap_a *
  page207_i41
#CELL
  mstr_discrete cap *
  page207_i42
#CELL
  mstr_discrete cap *
  page207_i43
#CELL
  mstr_discrete cap *
  page207_i44
#ISCELL
  mstr_standard offpage *
  page207_i45
#CELL
  mstr_discrete cap *
  page207_i48
#ISCELL
  mstr_symbols gnd *
  page207_i49
#CELL
  mstr_discrete cap *
  page207_i50
#CELL
  mstr_discrete cap *
  page207_i51
#ISCELL
  mstr_standard offpage *
  page207_i52
#ISCELL
  mstr_symbols vcc_core *
  page207_i53
#CELL
  mstr_discrete cap *
  page207_i54
#ISCELL
  mstr_symbols gnd *
  page207_i55
#ISCELL
  mstr_symbols p5v_stby *
  page207_i56
#ISCELL
  mstr_symbols p5v_stby *
  page207_i57
#CELL
  dev_discrete cap_a *
  page207_i58
#CELL
  dev_discrete cap_a *
  page207_i59
#ISCELL
  mstr_standard offpage *
  page207_i62
#ISCELL
  mstr_standard offpage *
  page207_i64
#CELL
  mstr_discrete res *
  page207_i67
#CELL
  mstr_discrete res *
  page207_i68
#ISCELL
  mstr_symbols gnd *
  page207_i69
#ISCELL
  mstr_symbols pvccin_cpu1 *
  page207_i7
#ISCELL
  mstr_symbols gnd *
  page207_i70
#CELL
  dev_discrete cap_a *
  page207_i71
#ISCELL
  mstr_symbols gnd *
  page207_i72
#CELL
  mstr_discrete cap *
  page207_i74
#ISCELL
  mstr_symbols gnd *
  page207_i75
#CELL
  w_hdl 3d01r5f-gp *
  page207_i76
#CELL
  w_hdl sc2k2p50v3kx-gp *
  page207_i77
#ISCELL
  mstr_symbols gnd *
  page207_i78
#CELL
  dev_discrete cap_a *
  page207_i8
#ISCELL
  mstr_symbols gnd *
  page207_i80
#CELL
  dev_discrete cap_a *
  page207_i81
#CELL
  mstr_discrete cap *
  page207_i82
#ISCELL
  mstr_symbols gnd *
  page207_i83
#CELL
  w_hdl sc2k2p50v3kx-gp *
  page207_i84
#CELL
  w_hdl 3d01r5f-gp *
  page207_i85
#ISCELL
  mstr_symbols gnd *
  page207_i86
#CELL
  mstr_discrete res *
  page207_i87
#CELL
  mstr_discrete res *
  page207_i88
#ISCELL
  mstr_symbols gnd *
  page207_i9
